FILE_TYPE = MACRO_DRAWING;
SET COLOR_WIRE YELLOW;
SET COLOR_PROP MONO;
SET COLOR_DOT WHITE;
SET COLOR_ARC YELLOW;
SET COLOR_BODY GREEN;
SET COLOR_NOTE MONO;
SET PROP_DISPLAY VALUE;
SET PAGE_NUMBER P165;
FORCEADD INTEL_CORP_BPAGE..1
(-875 -25);
FORCEPROP 1 LAST CDS_CON_LAST_MODIFIED Fri Jun 16 17:49:01 2017
J 0
(-2300 300);
DISPLAY 1.361702 (-2300 300);
PAINT GREEN (-2300 300);
DISPLAY INVISIBLE (-2300 300);
FORCEPROP 1 LAST CUSTOM_TXT_CDS <CURRENT_DESIGN_SHEET> OF <TOTAL_DESIGN_SHEETS>
J 0
(-1375 0);
PAINT ORANGE (-1375 0);
FORCEPROP 1 LAST CUSTOM_TXT_CDS <CON_LAST_MODIFIED>
J 0
(-4875 75);
PAINT ORANGE (-4875 75);
FORCEPROP 2 LAST CUSTOM_TXT_CDS <XR_PAGE_TITLE>
J 0
(-8765 5225);
DISPLAY 0.638298 (-8765 5225);
PAINT PINK (-8765 5225);
DISPLAY INVISIBLE (-8765 5225);
FORCEPROP 1 LAST SCH_TITLE VOLTAGE MONITORING IC
J 0
(-8825 25);
DISPLAY 1.212766 (-8825 25);
PAINT ORANGE (-8825 25);
FORCEPROP 1 LAST COMMENT_BODY TRUE
J 0
(-863 -13);
DISPLAY 0.617021 (-863 -13);
PAINT GREEN (-863 -13);
DISPLAY INVISIBLE (-863 -13);
FORCEPROP 2 LAST CDS_LIB mstr_symbols
J 0
(-875 -25);
DISPLAY 1.361702 (-875 -25);
PAINT ORANGE (-875 -25);
DISPLAY INVISIBLE (-875 -25);
FORCEPROP 2 LAST PAGE_BORDER TRUE
J 0
(-8765 5225);
DISPLAY 0.851064 (-8765 5225);
PAINT PINK (-8765 5225);
DISPLAY INVISIBLE (-8765 5225);
FORCEPROP 2 LAST CDS_XR_PAGE_TITLE CR-165 : @BASEBOARD_FAB2_LIB.BASEBOARD_FAB2(SCH_1):PAGE165
J 0
(-8765 5225);
DISPLAY 0.638298 (-8765 5225);
PAINT PINK (-8765 5225);
DISPLAY INVISIBLE (-8765 5225);
WIRE 3 682 (-7200 4075)(-7200 1150);
WIRE 3 682 (-2550 1150)(-7200 1150);
WIRE 3 682 (-7200 4075)(-2550 4075);
WIRE 3 682 (-2550 4075)(-2550 1150);
FORCENOTE
TP FAB1 DELETE ADC128D818 AND RELATED COMPONENT (NO USE IE) 0118
(-7100 1200) 0;
DISPLAY LEFT (-7100 1200);
DISPLAY 1.021277 (-7100 1200);
PAINT RED (-7100 1200);
FORCENOTE
ROOM=HEC_VOLT_MONITOR
(-8825 225) 0;
DISPLAY LEFT (-8825 225);
DISPLAY 1.361702 (-8825 225);
PAINT PURPLE (-8825 225);
FORCENOTE
BOM_COST=SM_HM
(-8825 125) 0;
DISPLAY LEFT (-8825 125);
DISPLAY 1.361702 (-8825 125);
PAINT PURPLE (-8825 125);
QUIT
